# T6G (Grand Teton) — schematic parts with pin connectivity, parts 8081–8081 of 8303; source: Cadence DE-HDL packaged netlist (pstxprt.dat, pstxnet.dat, pstchip.dat)

U25  GENOA_SP5  SOCKET6096_13568-001 IO  pkg SOCKET6096_93-4X120-45XA  page 10  (pins 4705-5040 of 6096)
  DF32  VSS_DF32  POWER  = GND
  DF33  AGPIO21  BI  = FM_BOARD_SKU_ID0
  DF34  \uart0_rts_l||uart2_rxd||agpio137\  BI  = TP_UART_CPU0_UART0_RTS_N
  DF35  VSS_DF35  POWER  = GND
  DF36  \agpio4||sata_act_l\  BI  = FM_PASSWORD_CLEAR_R_N
  DF37  VSS_DF37  POWER  = GND
  DF39  VSS_DF39  POWER  = GND
  DF40  \agpio5||devslp0||sata_zp0_l\  BI  = FM_SMM_CRASHDUMP
  DF41  TEST4_CCD14  TRI  = NC
  DF42  VSS_DF42  POWER  = GND
  DF43  VSS_DF43  POWER  = GND
  DF44  VSS_DF44  POWER  = GND
  DF45  VSS_DF45  POWER  = GND
  DF46  VSS_DF46  POWER  = GND
  DF47  VSS_DF47  POWER  = GND
  DF48  VSS_DF48  POWER  = GND
  DF49  VSS_DF49  POWER  = GND
  DF50  VSS_DF50  POWER  = GND
  DF51  VSS_DF51  POWER  = GND
  DF52  VSS_DF52  POWER  = GND
  DF53  VSS_DF53  POWER  = GND
  DF54  VSS_DF54  POWER  = GND
  DF55  MCB_DATA31  BI  = M_C_CPU0_SB_DQ<31>
  DF56  VSS_DF56  POWER  = GND
  DF57  VSS_DF57  POWER  = GND
  DF58  VSS_DF58  POWER  = GND
  DF59  VSS_DF59  POWER  = GND
  DF60  MDB_DATA31  BI  = M_D_CPU0_SB_DQ<31>
  DF61  VSS_DF61  POWER  = GND
  DF62  MBB_DATA31  BI  = M_B_CPU0_SB_DQ<31>
  DF63  VSS_DF63  POWER  = GND
  DF64  VSS_DF64  POWER  = GND
  DF65  VSS_DF65  POWER  = GND
  DF66  VSS_DF66  POWER  = GND
  DF67  MFB_DATA31  BI  = M_F_CPU0_SB_DQ<31>
  DF68  VSS_DF68  POWER  = GND
  DF69  MEB_DATA31  BI  = M_E_CPU0_SB_DQ<31>
  DF70  VSS_DF70  POWER  = GND
  DF71  VSS_DF71  POWER  = GND
  DF72  VSS_DF72  POWER  = GND
  DF73  VSS_DF73  POWER  = GND
  DF74  MAB_DATA31  BI  = M_A_CPU0_SB_DQ<31>
  DG1  VSS_DG1  POWER  = GND
  DG2  VSS_DG2  POWER  = GND
  DG3  VDDCR_CPU1_SENSE  POWER  = VSENSE_PVDDCR_CPU1_P0_DP
  DG4  SLP_S5_L  OUT  = CPU0_SLP_S5_N
  DG5  VDD_11_S3_DG5  POWER  = PVDD11_S3_P0
  DG6  VSS_DG6  POWER  = GND
  DG7  VSS_DG7  POWER  = GND
  DG8  VSS_DG8  POWER  = GND
  DG9  VSS_DG9  POWER  = GND
  DG10  RSMRST_L  IN  = RST_CPU0_RSMRST_N
  DG11  AGPIO87  BI  = NC
  DG12  \i2c4_scl||hp_scl||ubm_scl||agpio13\  BI  = SMB_CPU0_4_R_SCL
  DG13  VSS_DG13  POWER  = GND
  DG14  VSS_DG14  POWER  = GND
  DG15  VSS_DG15  POWER  = GND
  DG16  VSS_DG16  POWER  = GND
  DG17  RSVD_DG17  TRI  = NC
  DG18  VSS_DG18  POWER  = GND
  DG19  VDDCR_CPU1_DG19  POWER  = PVDDCR_CPU1_P0
  DG20  VSS_DG20  POWER  = GND
  DG21  VSS_DG21  POWER  = GND
  DG22  \espi0_dat1||spi0_dat1||agpio121\  BI  = SPI_CPU0_R_D1
  DG23  \espi_clk1||spi_clk1||agpio75\  BI  = CLK_ESPI_CPU0_R_CLK1
  DG24  VSS_DG24  POWER  = GND
  DG25  \espi1_dat3||spi1_dat3||agpio134\  BI  = ESPI_CPU0_R_D3
  DG26  \spi_cs1_l||agpio119\  BI  = SPI_CPU0_R_CS1_N
  DG27  VSS_DG27  POWER  = GND
  DG28  \espi_cs0_l||agpio124\  BI  = CPU0_ESPI_CS0_N
  DG29  \espi0_dat3||spi0_dat3||agpio123\  BI  = SPI_CPU0_R_D3
  DG30  VSS_DG30  POWER  = GND
  DG31  AGPIO107  BI  = FM_BOARD_SKU_ID3
  DG32  AGPIO109  BI  = CPU0_ROM_TYPE_SELECT
  DG33  VSS_DG33  POWER  = GND
  DG34  \uart0_intr||agpio139\  BI  = TP_CPU0_UART0_INTR
  DG35  \uart0_rxd||agpio136\  BI  = UART_CPU0_UART0_RX
  DG36  \pcie_rst1_l||agpio26\  BI  = RST_CPU0_PERST1_N
  DG40  \usb10_oc_l||agpio16\  BI  = NC
  DG41  VSS_DG41  POWER  = GND
  DG42  TEST5_CCD14  TRI  = NC
  DG43  VSS_DG43  POWER  = GND
  DG44  P4_RXN3  IN  = P3E_CPU0_P4_RX_DN<3>
  DG45  P4_RXP3  IN  = P3E_CPU0_P4_RX_DP<3>
  DG46  VSS_DG46  POWER  = GND
  DG47  P4_RXN2  IN  = P3E_CPU0_P4_RX_DN<2>
  DG48  P4_RXP2  IN  = P3E_CPU0_P4_RX_DP<2>
  DG49  VSS_DG49  POWER  = GND
  DG50  P4_RXN1  IN  = P3E_CPU0_P4_RX_DN<1>
  DG51  P4_RXP1  IN  = P3E_CPU0_P4_RX_DP<1>
  DG52  VSS_DG52  POWER  = GND
  DG53  P4_RXN0  IN  = P3E_CPU0_P4_RX_DN<0>
  DG54  P4_RXP0  IN  = P3E_CPU0_P4_RX_DP<0>
  DG55  VSS_DG55  POWER  = GND
  DG56  VSS_DG56  POWER  = GND
  DG57  VDDCR_CPU1_DG57  POWER  = PVDDCR_CPU1_P0
  DG58  USB11_TXP  OUT  = NC
  DG59  VSS_DG59  POWER  = GND
  DG60  VSS_DG60  POWER  = GND
  DG61  VSS_DG61  POWER  = GND
  DG62  VSS_DG62  POWER  = GND
  DG63  VSS_DG63  POWER  = GND
  DG64  VDDIO_DG64  POWER  = PVDDIO_P0
  DG65  VSS_DG65  POWER  = GND
  DG66  VSS_DG66  POWER  = GND
  DG67  VSS_DG67  POWER  = GND
  DG68  VSS_DG68  POWER  = GND
  DG69  VSS_DG69  POWER  = GND
  DG70  VSS_DG70  POWER  = GND
  DG71  VDDIO_DG71  POWER  = PVDDIO_P0
  DG72  PCC1_L  IN  = FM_P0_PCC1_N
  DG73  SVT1  IN  = SVID_PVDDCR_CPU1_P0_SVTO
  DG74  VSS_DG74  POWER  = GND
  DG75  VSS_DG75  POWER  = GND
  DH3  VDD_11_S3_SENSE  POWER  = VSENSE_PVDD11_S3_P0_DP
  DH4  AGPIO7  BI  = FM_BOARD_SKU_ID4
  DH5  VSS_DH5  POWER  = GND
  DH6  \sys_reset_l||agpio1\  BI  = RST_CPU0_SYS_N
  DH7  \pwr_btn_l||agpio0\  BI  = CPU0_PWR_BTN_N
  DH8  RTC_LDO_SELECT  IN  = CPU0_RTC_LDO_SELECT
  DH9  RTCCLK  BI  = CLK_CPU0_RTCCLK
  DH10  SP5R4  OUT  = CPU0_SP5R4
  DH11  VSS_DH11  POWER  = GND
  DH12  \i2c4_sda||hp_sda||ubm_sda||agpio14\  BI  = SMB_CPU0_4_R_SDA
  DH13  TEST4_CCD13  TRI  = NC
  DH14  TEST5_CCD13  TRI  = NC
  DH15  \agpio116||clk_req12_l\  BI  = IRQ_TPM_SPI_R_N
  DH16  \agpio115||clk_req11_l\  BI  = IRQ_SMI_ACTIVE_N
  DH17  RSVD_DH17  TRI  = NC
  DH18  VSS_DH18  POWER  = GND
  DH19  VDDCR_CPU1_DH19  POWER  = PVDDCR_CPU1_P0
  DH20  VDDCR_CPU1_DH20  POWER  = PVDDCR_CPU1_P0
  DH21  RSVD_DH21  TRI  = NC
  DH22  VDDCR_CPU1_DH22  POWER  = PVDDCR_CPU1_P0
  DH23  VDDCR_CPU1_DH23  POWER  = PVDDCR_CPU1_P0
  DH24  \espi1_dat0||spi1_dat0||agpio131\  BI  = ESPI_CPU0_R_D0
  DH25  VDDCR_CPU1_DH25  POWER  = PVDDCR_CPU1_P0
  DH26  VDDCR_CPU1_DH26  POWER  = PVDDCR_CPU1_P0
  DH27  \spi_cs2_l||agpio126\  BI  = NC_CPU0_SPI_CS2_N
  DH28  VDDCR_CPU1_DH28  POWER  = PVDDCR_CPU1_P0
  DH29  VDDCR_CPU1_DH29  POWER  = PVDDCR_CPU1_P0
  DH30  AGPIO104  BI  = BOOT_RDY_R_H
  DH31  VDDCR_CPU1_DH31  POWER  = PVDDCR_CPU1_P0
  DH32  VDDCR_CPU1_DH32  POWER  = PVDDCR_CPU1_P0
  DH33  \uart1_rxd||agpio141\  BI  = UART_CPU0_SCM_UART1_RX
  DH34  VDDCR_CPU1_DH34  POWER  = PVDDCR_CPU1_P0
  DH35  VDDCR_CPU1_DH35  POWER  = PVDDCR_CPU1_P0
  DH36  \pwrgd_out||agpio12\  BI  = CPU0_PWR_GD_OUT
  DH37  VSS_DH37  POWER  = GND
  DH39  VSS_DH39  POWER  = GND
  DH40  \usb11_oc_l||agpio17\  BI  = NC
  DH41  VDDCR_CPU1_DH41  POWER  = PVDDCR_CPU1_P0
  DH42  VDDCR_CPU1_DH42  POWER  = PVDDCR_CPU1_P0
  DH43  VSS_DH43  POWER  = GND
  DH44  VDDCR_CPU1_DH44  POWER  = PVDDCR_CPU1_P0
  DH45  VDDCR_CPU1_DH45  POWER  = PVDDCR_CPU1_P0
  DH46  VSS_DH46  POWER  = GND
  DH47  VDDCR_CPU1_DH47  POWER  = PVDDCR_CPU1_P0
  DH48  VDDCR_CPU1_DH48  POWER  = PVDDCR_CPU1_P0
  DH49  VSS_DH49  POWER  = GND
  DH50  VDDCR_CPU1_DH50  POWER  = PVDDCR_CPU1_P0
  DH51  VDDCR_CPU1_DH51  POWER  = PVDDCR_CPU1_P0
  DH52  VSS_DH52  POWER  = GND
  DH53  VDDCR_CPU1_DH53  POWER  = PVDDCR_CPU1_P0
  DH54  VDDCR_CPU1_DH54  POWER  = PVDDCR_CPU1_P0
  DH55  VSS_DH55  POWER  = GND
  DH56  VDDCR_CPU1_DH56  POWER  = PVDDCR_CPU1_P0
  DH57  VDDCR_CPU1_DH57  POWER  = PVDDCR_CPU1_P0
  DH58  USB11_TXN  OUT  = NC
  DH59  VSS_DH59  POWER  = GND
  DH60  USB11_DP  BI  = USB2_CPU0_P11_DP
  DH61  VSS_DH61  POWER  = GND
  DH62  USB11_RXN  IN  = NC
  DH63  VSS_DH63  POWER  = GND
  DH64  VSS_DH64  POWER  = GND
  DH65  USB10_RXN  IN  = NC
  DH66  VSS_DH66  POWER  = GND
  DH67  USB10_DN  BI  = USB2_CPU0_P10_DN
  DH68  VSS_DH68  POWER  = GND
  DH69  USB10_TXP  OUT  = NC
  DH70  VSS_DH70  POWER  = GND
  DH71  SID  BI  = SMB_APML_CPU0_SDA
  DH72  SVD1  BI  = SVID_PVDDCR_CPU1_P0_SVD
  DH73  SP5R3  OUT  = CPU0_SP5R3
  DJ3  VSS_SENSE_C  POWER  = VSENSE_VSS_SENSE_C_P0
  DJ4  RSVD_DJ4  TRI  = NC
  DJ5  SLP_S3_L  OUT  = CPU0_SLP_S3_N
  DJ7  VSS_DJ7  POWER  = GND
  DJ8  PWR_GOOD  IN  = CPU0_PWR_GOOD
  DJ9  THERMTRIP_L  OUT  = CPU0_THERMTRIP_N
  DJ10  \wake_l||agpio2\  BI  = IRQ_WAKE_N
  DJ11  \smerr_l||agpio24\  BI  = CPU0_SMERR_N
  DJ13  X32K_X2  IN  = XTAL_CPU0_X32K_X2
  DJ14  X32K_X1  IN  = XTAL_CPU0_X32K_X1
  DJ15  VSS_DJ15  POWER  = GND
  DJ16  X48M_X2  IN  = XTAL_CPU0_X48M_X2
  DJ17  X48M_X1  IN  = XTAL_CPU0_X48M_X1
  DJ19  VSS_DJ19  POWER  = GND
  DJ20  \i2c5_sda||bmc_sda||smbus1_sda||agpio20\  BI  = SMB_CPU_5_R_SDA
  DJ21  \i2c5_scl||bmc_scl||smbus1_scl||agpio19\  BI  = SMB_CPU_5_R_SCL
  DJ22  \espi0_alert_l||agpio108\  BI  = CPU0_ESPI0_ALERT_N
  DJ23  \espi_cs1_l||agpio125\  BI  = ESPI_CPU0_R_CS1_N
  DJ25  \agpio76||spi_tpm_cs_l\  BI  = SPI_CPU0_R_TPM_CS_N
  DJ26  \espi_rstin_l||kbrst_l||agpio129\  BI  = RST_CPU0_KBRST_R_N
  DJ27  \espi_clk0||spi_clk0||agpio117\  BI  = SPI_CPU0_R_CLK
  DJ28  \espi0_dat2||spi0_dat2||agpio122\  BI  = SPI_CPU0_R_D2
  DJ29  AGPIO88  BI  = FM_BIOS_POST_CMPLT_R_N
  DJ31  NMI_SYNC_FLOOD_L  IN  = CPU0_NMI_SYNC_FLOOD_N
  DJ32  \uart1_txd||agpio142\  BI  = UART_CPU0_SCM_UART1_R_TX
  DJ33  \uart0_cts_l||uart2_txd||agpio135\  BI  = FM_BIOS_USB_RECOVERY_R
  DJ34  \uart0_txd||agpio138\  BI  = UART_CPU0_UART0_R_TX
  DJ35  \genint_l||pm_intr_l||ubm_cprsnt_change_det_l||agpio89\  BI  = FM_INT_CPU0_HP_UBM_N
  DJ41  GPP_CLK11P  OUT  = CLK_100M_CPU0_CLK11_R_DP
  DJ42  GPP_CLK11N  OUT  = CLK_100M_CPU0_CLK11_R_DN
  DJ43  VSS_DJ43  POWER  = GND
  DJ44  GPP_CLK12N  OUT  = CLK_100M_CPU0_CLK12_R_DN
  DJ45  GPP_CLK12P  OUT  = CLK_100M_CPU0_CLK12_R_DP
  DJ47  GPP_CLK14N  OUT  = NC
  DJ48  GPP_CLK14P  OUT  = NC
  DJ49  VSS_DJ49  POWER  = GND
  DJ50  GPP_CLK15N  OUT  = NC
  DJ51  GPP_CLK15P  OUT  = NC
  DJ53  GPP_CLK13P  OUT  = CLK_100M_CPU0_CLK13_R_DP
  DJ54  GPP_CLK13N  OUT  = CLK_100M_CPU0_CLK13_R_DN
  DJ55  SA0  IN  = CPU0_SA0
  DJ56  SA1  IN  = CPU0_SA1
  DJ57  TEST6_X3D7  OUT  = NC
  DJ59  VSS_DJ59  POWER  = GND
  DJ60  USB11_DN  BI  = USB2_CPU0_P11_DN
  DJ61  VSS_DJ61  POWER  = GND
  DJ62  USB11_RXP  IN  = NC
  DJ63  VSS_DJ63  POWER  = GND
  DJ65  USB10_RXP  IN  = NC
  DJ66  VSS_DJ66  POWER  = GND
  DJ67  USB10_DP  BI  = USB2_CPU0_P10_DP
  DJ68  VSS_DJ68  POWER  = GND
  DJ69  USB10_TXN  OUT  = NC
  DJ71  SIC  OUT  = SMB_APML_CPU0_SCL
  DJ72  SVC1  OUT  = SVID_PVDDCR_CPU1_P0_SVC
  DJ73  VSS_DJ73  POWER  = GND
  E1  VSS_E1  POWER  = GND
  E2  MGA_DATA0  BI  = M_G_CPU0_SA_DQ<0>
  E3  VSS_E3  POWER  = GND
  E4  VDDCR_SOC_E4  POWER  = PVDDCR_SOC_P0
  E5  MKA_DATA0  BI  = M_K_CPU0_SA_DQ<0>
  E6  VSS_E6  POWER  = GND
  E7  VSS_E7  POWER  = GND
  E8  VSS_E8  POWER  = GND
  E9  MLA_DATA0  BI  = M_L_CPU0_SA_DQ<0>
  E10  VSS_E10  POWER  = GND
  E11  VDDCR_SOC_E11  POWER  = PVDDCR_SOC_P0
  E12  MHA_DATA0  BI  = M_H_CPU0_SA_DQ<0>
  E13  VSS_E13  POWER  = GND
  E14  VSS_E14  POWER  = GND
  E15  VSS_E15  POWER  = GND
  E16  MJA_DATA0  BI  = M_J_CPU0_SA_DQ<0>
  E17  VSS_E17  POWER  = GND
  E18  VSS_E18  POWER  = GND
  E19  MIA_DATA0  BI  = M_I_CPU0_SA_DQ<0>
  E20  VSS_E20  POWER  = GND
  E21  VSS_E21  POWER  = GND
  E22  VDDCR_CPU0_E22  POWER  = PVDDCR_CPU0_P0
  E23  \usb00_oc_l||agpio264\  BI  = SCM_USB_OC_BUF_N
  E24  \usb01_oc_l||agpio265\  BI  = NC
  E25  VDDCR_CPU0_E25  POWER  = PVDDCR_CPU0_P0
  E26  USB00_RXN  IN  = USB3_CPU0_BMC_RX_HUB_C_DN
  E27  USB00_RXP  IN  = USB3_CPU0_BMC_RX_HUB_C_DP
  E28  VDDCR_CPU0_E28  POWER  = PVDDCR_CPU0_P0
  E29  USB01_TXN  OUT  = NC
  E30  USB01_TXP  OUT  = NC
  E31  VDDCR_CPU0_E31  POWER  = PVDDCR_CPU0_P0
  E32  TEST47_CCD3  TRI  = TP_CPU0_TEST47_CCD3
  E33  RSVD_E33  TRI  = NC
  E34  VDDCR_CPU0_E34  POWER  = PVDDCR_CPU0_P0
  E35  VDDCR_CPU0_E35  POWER  = PVDDCR_CPU0_P0
  E36  RSVD_E36  TRI  = NC
  E40  P5_RXP3  IN  = NC
  E41  P5_RXN3  IN  = NC
  E42  VDDCR_CPU0_E42  POWER  = PVDDCR_CPU0_P0
  E43  P5_RXP2  IN  = P2E_CPU0_P5_RX_DP
  E44  P5_RXN2  IN  = P2E_CPU0_P5_RX_DN
  E45  VDDCR_CPU0_E45  POWER  = PVDDCR_CPU0_P0
  E46  \wafl_rxp1||p5_rxp1\  IN  = NC
  E47  \wafl_rxn1||p5_rxn1\  IN  = NC
  E48  VDDCR_CPU0_E48  POWER  = PVDDCR_CPU0_P0
  E49  \wafl_rxp0||p5_rxp0\  IN  = WAFL_CPU1_TX1_CPU0_RX0_DP
  E50  \wafl_rxn0||p5_rxn0\  IN  = WAFL_CPU1_TX1_CPU0_RX0_DN
  E51  VDDCR_CPU0_E51  POWER  = PVDDCR_CPU0_P0
  E52  VSS_E52  POWER  = GND
  E53  VSS_E53  POWER  = GND
  E54  VDDCR_CPU0_E54  POWER  = PVDDCR_CPU0_P0
  E55  VSS_E55  POWER  = GND
  E56  VSS_E56  POWER  = GND
  E57  MCA_DATA0  BI  = M_C_CPU0_SA_DQ<0>
  E58  VSS_E58  POWER  = GND
  E59  VSS_E59  POWER  = GND
  E60  MDA_DATA0  BI  = M_D_CPU0_SA_DQ<0>
  E61  VSS_E61  POWER  = GND
  E62  VSS_E62  POWER  = GND
  E63  VSS_E63  POWER  = GND
  E64  MBA_DATA0  BI  = M_B_CPU0_SA_DQ<0>
  E65  VSS_E65  POWER  = GND
  E66  VSS_E66  POWER  = GND
  E67  MFA_DATA0  BI  = M_F_CPU0_SA_DQ<0>
  E68  VSS_E68  POWER  = GND
  E69  VSS_E69  POWER  = GND
  E70  VSS_E70  POWER  = GND
  E71  MEA_DATA0  BI  = M_E_CPU0_SA_DQ<0>
  E72  VSS_E72  POWER  = GND
  E73  VSS_E73  POWER  = GND
  E74  MAA_DATA0  BI  = M_A_CPU0_SA_DQ<0>
  E75  VSS_E75  POWER  = GND
  F2  MGA_DATA2  BI  = M_G_CPU0_SA_DQ<2>
  F3  VSS_F3  POWER  = GND
  F4  MGA_DATA1  BI  = M_G_CPU0_SA_DQ<1>
  F5  VSS_F5  POWER  = GND
  F6  MKA_DATA2  BI  = M_K_CPU0_SA_DQ<2>
  F7  MKA_DATA1  BI  = M_K_CPU0_SA_DQ<1>
  F8  VSS_F8  POWER  = GND
  F9  MLA_DATA2  BI  = M_L_CPU0_SA_DQ<2>
  F10  VSS_F10  POWER  = GND
  F11  MLA_DATA1  BI  = M_L_CPU0_SA_DQ<1>
  F12  VSS_F12  POWER  = GND
  F13  MHA_DATA2  BI  = M_H_CPU0_SA_DQ<2>
  F14  MHA_DATA1  BI  = M_H_CPU0_SA_DQ<1>
  F15  VSS_F15  POWER  = GND
  F16  MJA_DATA2  BI  = M_J_CPU0_SA_DQ<2>
  F17  VSS_F17  POWER  = GND
  F18  MJA_DATA1  BI  = M_J_CPU0_SA_DQ<1>
  F19  VSS_F19  POWER  = GND
  F20  MIA_DATA2  BI  = M_I_CPU0_SA_DQ<2>
  F21  MIA_DATA1  BI  = M_I_CPU0_SA_DQ<1>
  F22  VDDCR_CPU0_F22  POWER  = PVDDCR_CPU0_P0
  F23  VSS_F23  POWER  = GND
  F24  VSS_F24  POWER  = GND
  F25  VDDCR_CPU0_F25  POWER  = PVDDCR_CPU0_P0
